(kicad_pcb
	(version 20260206)
	(generator "pcbnew")
	(generator_version "10.0")
	(general
		(thickness 1.6)
		(legacy_teardrops no)
	)
	(paper "A4")
	(title_block
		(title "peb — Lightning_PEB_BRD.brd")
		(comment 1 "Lightning (Wiwynn / Facebook NVMe JBOF) / footprints 1586-1593 of 2563")
	)
	(layers
		(0 "F.Cu" signal "TOP")
		(4 "In1.Cu" signal "L2GND")
		(6 "In2.Cu" signal "L3")
		(8 "In3.Cu" signal "L4VCC")
		(10 "In4.Cu" signal "L5VCC")
		(12 "In5.Cu" signal "L6")
		(14 "In6.Cu" signal "L7GND")
		(2 "B.Cu" signal "BOTTOM")
		(9 "F.Adhes" user "F.Adhesive")
		(11 "B.Adhes" user "B.Adhesive")
		(13 "F.Paste" user "Package Geometry/Pastemask Top")
		(15 "B.Paste" user "Package Geometry/Pastemask Bottom")
		(5 "F.SilkS" user "Ref Des/Silkscreen Top")
		(7 "B.SilkS" user "Ref Des/Silkscreen Bottom")
		(1 "F.Mask" user "Board Geometry/Soldermask Top")
		(3 "B.Mask" user "Board Geometry/Soldermask Bottom")
		(17 "Dwgs.User" user "User.Drawings")
		(19 "Cmts.User" user "User.Comments")
		(21 "Eco1.User" user "User.Eco1")
		(23 "Eco2.User" user "User.Eco2")
		(25 "Edge.Cuts" user "Board Geometry/Outline")
		(27 "Margin" user)
		(31 "F.CrtYd" user "Package Geometry/Place Bound Top")
		(29 "B.CrtYd" user "Package Geometry/Place Bound Bottom")
		(35 "F.Fab" user "Ref Des/Assembly Top")
		(33 "B.Fab" user "Ref Des/Assembly Bottom")
	)
	(footprint ""
		(layer "F.Cu")
		(at 293.191946 -212.420454 180)
		(property "Reference" "C79"
			(at 0 0 180)
			(layer "F.SilkS")
			(hide yes)
			(effects
				(font
					(size 1.27 1.27)
				)
			)
		)
		(property "Value" "SCD22U10V2KX-1GP"
			(at 1.1811 -2.7051 180)
			(unlocked yes)
			(layer "F.Fab")
			(hide yes)
			(effects
				(font
					(size 1.016 1.016)
					(thickness 0.1524)
				)
			)
		)
		(property "Device Type" "C402H22"
			(at 1.1811 -4.2291 180)
			(unlocked yes)
			(layer "F.Fab")
			(hide yes)
			(effects
				(font
					(size 1.016 1.016)
					(thickness 0.1524)
				)
			)
		)
		(duplicate_pad_numbers_are_jumpers no)
		(fp_rect
			(start -0.4318 0.9525)
			(end 0.4318 -0.9525)
			(stroke
				(width 0)
				(type default)
			)
			(fill no)
			(layer "F.CrtYd")
		)
		(fp_rect
			(start -0.4318 0.9525)
			(end 0.4318 -0.9525)
			(stroke
				(width 0)
				(type default)
			)
			(fill no)
			(layer "F.Fab")
		)
		(pad "1" smd custom
			(at 0 -0.4445 180)
			(size 0.1524 0.1524)
			(layers "F.Cu" "F.Mask" "F.Paste")
			(net "PCIE_TX_CAP_P28")
			(options
				(clearance outline)
				(anchor circle)
			)
			(primitives
				(gr_poly
					(pts
						(arc
							(start 0.3048 -0.2032)
							(mid 0.275042 -0.275042)
							(end 0.2032 -0.3048)
						)
						(arc
							(start -0.2032 -0.3048)
							(mid -0.275042 -0.275042)
							(end -0.3048 -0.2032)
						)
						(arc
							(start -0.3048 0.2032)
							(mid -0.275042 0.275042)
							(end -0.2032 0.3048)
						)
						(arc
							(start 0.2032 0.3048)
							(mid 0.275042 0.275042)
							(end 0.3048 0.2032)
						)
					)
					(width 0)
					(fill yes)
				)
			)
		)
		(pad "2" smd custom
			(at 0 0.4445 180)
			(size 0.1524 0.1524)
			(layers "F.Cu" "F.Mask" "F.Paste")
			(net "PCIE_TX_P28")
			(options
				(clearance outline)
				(anchor circle)
			)
			(primitives
				(gr_poly
					(pts
						(arc
							(start 0.3048 -0.2032)
							(mid 0.275042 -0.275042)
							(end 0.2032 -0.3048)
						)
						(arc
							(start -0.2032 -0.3048)
							(mid -0.275042 -0.275042)
							(end -0.3048 -0.2032)
						)
						(arc
							(start -0.3048 0.2032)
							(mid -0.275042 0.275042)
							(end -0.2032 0.3048)
						)
						(arc
							(start 0.2032 0.3048)
							(mid 0.275042 0.275042)
							(end 0.3048 0.2032)
						)
					)
					(width 0)
					(fill yes)
				)
			)
		)
	)
	(footprint ""
		(layer "F.Cu")
		(at 51.943 -124.46)
		(property "Reference" "TP178"
			(at 0 0 0)
			(layer "F.SilkS")
			(hide yes)
			(effects
				(font
					(size 1.27 1.27)
				)
			)
		)
		(property "Value" "TPAD28-2-GP"
			(at -0.0127 -1.6637 0)
			(unlocked yes)
			(layer "F.Fab")
			(hide yes)
			(effects
				(font
					(size 1.016 1.016)
					(thickness 0.1524)
				)
			)
		)
		(property "Device Type" "TPAD28"
			(at -0.0127 -3.1877 0)
			(unlocked yes)
			(layer "F.Fab")
			(hide yes)
			(effects
				(font
					(size 1.016 1.016)
					(thickness 0.1524)
				)
			)
		)
		(duplicate_pad_numbers_are_jumpers no)
		(fp_poly
			(pts
				(arc
					(start 0.3556 0)
					(mid -0.3556 0)
					(end 0.3556 0)
				)
			)
			(stroke
				(width 0)
				(type default)
			)
			(fill no)
			(layer "F.CrtYd")
		)
		(fp_poly
			(pts
				(arc
					(start 0.6096 0)
					(mid -0.6096 0)
					(end 0.6096 0)
				)
			)
			(stroke
				(width 0)
				(type default)
			)
			(fill no)
			(layer "F.Fab")
		)
		(pad "1" smd circle
			(at 0 0)
			(size 0.7112 0.7112)
			(layers "F.Cu" "F.Mask" "F.Paste")
			(net "JTAG_BMC_TCK")
		)
	)
	(footprint ""
		(layer "F.Cu")
		(at 204.3684 -27.0002 -90)
		(property "Reference" "C135"
			(at 0 0 270)
			(layer "F.SilkS")
			(hide yes)
			(effects
				(font
					(size 1.27 1.27)
				)
			)
		)
		(property "Value" "SCD047U25V2KX-GP"
			(at 1.1811 -2.7051 270)
			(unlocked yes)
			(layer "F.Fab")
			(hide yes)
			(effects
				(font
					(size 1.016 1.016)
					(thickness 0.1524)
				)
			)
		)
		(property "Device Type" "C402H22"
			(at 1.1811 -4.2291 270)
			(unlocked yes)
			(layer "F.Fab")
			(hide yes)
			(effects
				(font
					(size 1.016 1.016)
					(thickness 0.1524)
				)
			)
		)
		(duplicate_pad_numbers_are_jumpers no)
		(fp_rect
			(start -0.4318 0.9525)
			(end 0.4318 -0.9525)
			(stroke
				(width 0)
				(type default)
			)
			(fill no)
			(layer "F.CrtYd")
		)
		(fp_rect
			(start -0.4318 0.9525)
			(end 0.4318 -0.9525)
			(stroke
				(width 0)
				(type default)
			)
			(fill no)
			(layer "F.Fab")
		)
		(pad "1" smd custom
			(at 0 -0.4445 270)
			(size 0.1524 0.1524)
			(layers "F.Cu" "F.Mask" "F.Paste")
			(net "P3V3_STBY")
			(options
				(clearance outline)
				(anchor circle)
			)
			(primitives
				(gr_poly
					(pts
						(arc
							(start 0.3048 -0.2032)
							(mid 0.275042 -0.275042)
							(end 0.2032 -0.3048)
						)
						(arc
							(start -0.2032 -0.3048)
							(mid -0.275042 -0.275042)
							(end -0.3048 -0.2032)
						)
						(arc
							(start -0.3048 0.2032)
							(mid -0.275042 0.275042)
							(end -0.2032 0.3048)
						)
						(arc
							(start 0.2032 0.3048)
							(mid 0.275042 0.275042)
							(end 0.3048 0.2032)
						)
					)
					(width 0)
					(fill yes)
				)
			)
		)
		(pad "2" smd custom
			(at 0 0.4445 270)
			(size 0.1524 0.1524)
			(layers "F.Cu" "F.Mask" "F.Paste")
			(net "GND")
			(options
				(clearance outline)
				(anchor circle)
			)
			(primitives
				(gr_poly
					(pts
						(arc
							(start 0.3048 -0.2032)
							(mid 0.275042 -0.275042)
							(end 0.2032 -0.3048)
						)
						(arc
							(start -0.2032 -0.3048)
							(mid -0.275042 -0.275042)
							(end -0.3048 -0.2032)
						)
						(arc
							(start -0.3048 0.2032)
							(mid -0.275042 0.275042)
							(end -0.2032 0.3048)
						)
						(arc
							(start 0.2032 0.3048)
							(mid 0.275042 0.275042)
							(end 0.3048 0.2032)
						)
					)
					(width 0)
					(fill yes)
				)
			)
		)
	)
	(footprint ""
		(layer "F.Cu")
		(at 215.06942 -31.274512)
		(property "Reference" "TP277"
			(at 0 0 0)
			(layer "F.SilkS")
			(hide yes)
			(effects
				(font
					(size 1.27 1.27)
				)
			)
		)
		(property "Value" "TPAD28-2-GP"
			(at -0.0127 -1.6637 0)
			(unlocked yes)
			(layer "F.Fab")
			(hide yes)
			(effects
				(font
					(size 1.016 1.016)
					(thickness 0.1524)
				)
			)
		)
		(property "Device Type" "TPAD28"
			(at -0.0127 -3.1877 0)
			(unlocked yes)
			(layer "F.Fab")
			(hide yes)
			(effects
				(font
					(size 1.016 1.016)
					(thickness 0.1524)
				)
			)
		)
		(duplicate_pad_numbers_are_jumpers no)
		(fp_poly
			(pts
				(arc
					(start 0.3556 0)
					(mid -0.3556 0)
					(end 0.3556 0)
				)
			)
			(stroke
				(width 0)
				(type default)
			)
			(fill no)
			(layer "F.CrtYd")
		)
		(fp_poly
			(pts
				(arc
					(start 0.6096 0)
					(mid -0.6096 0)
					(end 0.6096 0)
				)
			)
			(stroke
				(width 0)
				(type default)
			)
			(fill no)
			(layer "F.Fab")
		)
		(pad "1" smd circle
			(at 0 0)
			(size 0.7112 0.7112)
			(layers "F.Cu" "F.Mask" "F.Paste")
			(net "LBI_DATA12_R")
		)
	)
	(footprint ""
		(layer "F.Cu")
		(at 199.323452 -22.6314 -90)
		(property "Reference" "U56"
			(at 0 0 270)
			(layer "F.SilkS")
			(hide yes)
			(effects
				(font
					(size 1.27 1.27)
				)
			)
		)
		(property "Value" "TCA9554PWR-GP"
			(at 0.127 -12.573 270)
			(unlocked yes)
			(layer "F.Fab")
			(hide yes)
			(effects
				(font
					(size 1.016 1.016)
					(thickness 0.1524)
				)
			)
		)
		(property "Device Type" "TSOIC16H48"
			(at 0.1016 -14.5796 270)
			(unlocked yes)
			(layer "F.Fab")
			(hide yes)
			(effects
				(font
					(size 1.016 1.016)
					(thickness 0.1524)
				)
			)
		)
		(duplicate_pad_numbers_are_jumpers no)
		(fp_line
			(start -2.921 3.81)
			(end -2.921 1.778)
			(stroke
				(width 0.508)
				(type default)
			)
			(layer "F.SilkS")
		)
		(fp_line
			(start 2.3622 1.778)
			(end -2.921 1.778)
			(stroke
				(width 0.1524)
				(type default)
			)
			(layer "F.SilkS")
		)
		(fp_line
			(start -2.54 0)
			(end -3.0988 0.5588)
			(stroke
				(width 0.1524)
				(type default)
			)
			(layer "F.SilkS")
		)
		(fp_line
			(start -2.54 0)
			(end -3.0988 -0.5588)
			(stroke
				(width 0.1524)
				(type default)
			)
			(layer "F.SilkS")
		)
		(fp_line
			(start -3.0988 -1.778)
			(end -3.0988 1.778)
			(stroke
				(width 0.1524)
				(type default)
			)
			(layer "F.SilkS")
		)
		(fp_line
			(start -3.0988 -1.778)
			(end 2.3622 -1.778)
			(stroke
				(width 0.1524)
				(type default)
			)
			(layer "F.SilkS")
		)
		(fp_line
			(start 2.3622 -1.778)
			(end 2.3622 1.778)
			(stroke
				(width 0.1524)
				(type default)
			)
			(layer "F.SilkS")
		)
		(fp_poly
			(pts
				(xy -2.4638 -1.778) (xy -2.4638 1.778) (xy 2.3622 1.778) (xy 2.3622 -1.778)
			)
			(stroke
				(width 0)
				(type default)
			)
			(fill yes)
			(layer "F.SilkS")
		)
		(fp_rect
			(start -3.175 4.064)
			(end 3.175 -4.064)
			(stroke
				(width 0)
				(type default)
			)
			(fill no)
			(layer "F.CrtYd")
		)
		(fp_poly
			(pts
				(xy -3.175 -4.064) (xy 3.175 -4.064) (xy 3.175 4.064) (xy -3.175 4.064)
			)
			(stroke
				(width 0)
				(type default)
			)
			(fill no)
			(layer "F.Fab")
		)
		(pad "1" smd rect
			(at -2.27584 2.8194 270)
			(size 0.3556 1.524)
			(layers "F.Cu" "F.Mask" "F.Paste")
			(net "U56_A0")
		)
		(pad "2" smd rect
			(at -1.6256 2.8194 270)
			(size 0.3556 1.524)
			(layers "F.Cu" "F.Mask" "F.Paste")
			(net "U56_A1")
		)
		(pad "3" smd rect
			(at -0.97536 2.8194 270)
			(size 0.3556 1.524)
			(layers "F.Cu" "F.Mask" "F.Paste")
			(net "U56_A2")
		)
		(pad "4" smd rect
			(at -0.32512 2.8194 270)
			(size 0.3556 1.524)
			(layers "F.Cu" "F.Mask" "F.Paste")
			(net "MINISAS_CN15_A_I2C_INT#")
		)
		(pad "5" smd rect
			(at 0.32512 2.8194 270)
			(size 0.3556 1.524)
			(layers "F.Cu" "F.Mask" "F.Paste")
			(net "MINISAS_CN15_B_I2C_INT#")
		)
		(pad "6" smd rect
			(at 0.97536 2.8194 270)
			(size 0.3556 1.524)
			(layers "F.Cu" "F.Mask" "F.Paste")
			(net "MINISAS_CN15_C_I2C_INT#")
		)
		(pad "7" smd rect
			(at 1.6256 2.8194 270)
			(size 0.3556 1.524)
			(layers "F.Cu" "F.Mask" "F.Paste")
			(net "MINISAS_CN15_D_I2C_INT#")
		)
		(pad "8" smd rect
			(at 2.27584 2.8194 270)
			(size 0.3556 1.524)
			(layers "F.Cu" "F.Mask" "F.Paste")
			(net "GND")
		)
		(pad "9" smd rect
			(at 2.27584 -2.8194 270)
			(size 0.3556 1.524)
			(layers "F.Cu" "F.Mask" "F.Paste")
			(net "MINISAS_CN16_A_I2C_INT#")
		)
		(pad "10" smd rect
			(at 1.6256 -2.8194 270)
			(size 0.3556 1.524)
			(layers "F.Cu" "F.Mask" "F.Paste")
			(net "MINISAS_CN16_B_I2C_INT#")
		)
		(pad "11" smd rect
			(at 0.97536 -2.8194 270)
			(size 0.3556 1.524)
			(layers "F.Cu" "F.Mask" "F.Paste")
			(net "MINISAS_CN16_C_I2C_INT#")
		)
		(pad "12" smd rect
			(at 0.32512 -2.8194 270)
			(size 0.3556 1.524)
			(layers "F.Cu" "F.Mask" "F.Paste")
			(net "MINISAS_CN16_D_I2C_INT#")
		)
		(pad "13" smd rect
			(at -0.32512 -2.8194 270)
			(size 0.3556 1.524)
			(layers "F.Cu" "F.Mask" "F.Paste")
			(net "U56_INT_N")
		)
		(pad "14" smd rect
			(at -0.97536 -2.8194 270)
			(size 0.3556 1.524)
			(layers "F.Cu" "F.Mask" "F.Paste")
			(net "U56_SCL")
		)
		(pad "15" smd rect
			(at -1.6256 -2.8194 270)
			(size 0.3556 1.524)
			(layers "F.Cu" "F.Mask" "F.Paste")
			(net "U56_SDA")
		)
		(pad "16" smd rect
			(at -2.27584 -2.8194 270)
			(size 0.3556 1.524)
			(layers "F.Cu" "F.Mask" "F.Paste")
			(net "P3V3_STBY")
		)
	)
	(footprint ""
		(layer "F.Cu")
		(at 123.19 -12.66952 90)
		(property "Reference" "SR709"
			(at 0 0 90)
			(layer "F.SilkS")
			(hide yes)
			(effects
				(font
					(size 1.27 1.27)
				)
			)
		)
		(property "Value" "150R2F-1-GP"
			(at 0.064008 -3.993896 90)
			(unlocked yes)
			(layer "F.Fab")
			(hide yes)
			(effects
				(font
					(size 1.016 1.016)
					(thickness 0.1524)
				)
			)
		)
		(property "Device Type" "R402H16"
			(at 0.064008 -5.517896 90)
			(unlocked yes)
			(layer "F.Fab")
			(hide yes)
			(effects
				(font
					(size 1.016 1.016)
					(thickness 0.1524)
				)
			)
		)
		(duplicate_pad_numbers_are_jumpers no)
		(fp_line
			(start 0.508 -0.9398)
			(end -0.508 -0.9398)
			(stroke
				(width 0.1524)
				(type default)
			)
			(layer "F.SilkS")
		)
		(fp_line
			(start -0.508 -0.9398)
			(end -0.508 0.9398)
			(stroke
				(width 0.1524)
				(type default)
			)
			(layer "F.SilkS")
		)
		(fp_rect
			(start -0.508 0.9398)
			(end 0.508 -0.9398)
			(stroke
				(width 0)
				(type default)
			)
			(fill no)
			(layer "F.CrtYd")
		)
		(fp_rect
			(start -0.508 0.9398)
			(end 0.508 -0.9398)
			(stroke
				(width 0)
				(type default)
			)
			(fill no)
			(layer "F.Fab")
		)
		(pad "1" smd custom
			(at 0 -0.4445 90)
			(size 0.1397 0.1397)
			(layers "F.Cu" "F.Mask" "F.Paste")
			(net "P3V3_STBY")
			(options
				(clearance outline)
				(anchor circle)
			)
			(primitives
				(gr_poly
					(pts
						(arc
							(start -0.1778 -0.2794)
							(mid -0.249642 -0.249642)
							(end -0.2794 -0.1778)
						)
						(arc
							(start -0.2794 0.1778)
							(mid -0.249642 0.249642)
							(end -0.1778 0.2794)
						)
						(arc
							(start 0.1778 0.2794)
							(mid 0.249642 0.249642)
							(end 0.2794 0.1778)
						)
						(arc
							(start 0.2794 -0.1778)
							(mid 0.249642 -0.249642)
							(end 0.1778 -0.2794)
						)
					)
					(width 0)
					(fill yes)
				)
			)
		)
		(pad "2" smd custom
			(at 0 0.4445 90)
			(size 0.1397 0.1397)
			(layers "F.Cu" "F.Mask" "F.Paste")
			(net "LED_R_2")
			(options
				(clearance outline)
				(anchor circle)
			)
			(primitives
				(gr_poly
					(pts
						(arc
							(start -0.1778 -0.2794)
							(mid -0.249642 -0.249642)
							(end -0.2794 -0.1778)
						)
						(arc
							(start -0.2794 0.1778)
							(mid -0.249642 0.249642)
							(end -0.1778 0.2794)
						)
						(arc
							(start 0.1778 0.2794)
							(mid 0.249642 0.249642)
							(end 0.2794 0.1778)
						)
						(arc
							(start 0.2794 -0.1778)
							(mid 0.249642 -0.249642)
							(end 0.1778 -0.2794)
						)
					)
					(width 0)
					(fill yes)
				)
			)
		)
	)
	(footprint ""
		(layer "F.Cu")
		(at 161.6202 -95.9104 180)
		(property "Reference" "R3109"
			(at 0 0 180)
			(layer "F.SilkS")
			(hide yes)
			(effects
				(font
					(size 1.27 1.27)
				)
			)
		)
		(property "Value" "27R2F-GP"
			(at 0.064008 -3.993896 180)
			(unlocked yes)
			(layer "F.Fab")
			(hide yes)
			(effects
				(font
					(size 1.016 1.016)
					(thickness 0.1524)
				)
			)
		)
		(property "Device Type" "R402H16"
			(at 0.064008 -5.517896 180)
			(unlocked yes)
			(layer "F.Fab")
			(hide yes)
			(effects
				(font
					(size 1.016 1.016)
					(thickness 0.1524)
				)
			)
		)
		(duplicate_pad_numbers_are_jumpers no)
		(fp_line
			(start 0.508 -0.9398)
			(end -0.508 -0.9398)
			(stroke
				(width 0.1524)
				(type default)
			)
			(layer "F.SilkS")
		)
		(fp_line
			(start -0.508 -0.9398)
			(end -0.508 0.9398)
			(stroke
				(width 0.1524)
				(type default)
			)
			(layer "F.SilkS")
		)
		(fp_rect
			(start -0.508 0.9398)
			(end 0.508 -0.9398)
			(stroke
				(width 0)
				(type default)
			)
			(fill no)
			(layer "F.CrtYd")
		)
		(fp_rect
			(start -0.508 0.9398)
			(end 0.508 -0.9398)
			(stroke
				(width 0)
				(type default)
			)
			(fill no)
			(layer "F.Fab")
		)
		(pad "1" smd custom
			(at 0 -0.4445 180)
			(size 0.1397 0.1397)
			(layers "F.Cu" "F.Mask" "F.Paste")
			(net "CLKGEN_N3_R")
			(options
				(clearance outline)
				(anchor circle)
			)
			(primitives
				(gr_poly
					(pts
						(arc
							(start -0.1778 -0.2794)
							(mid -0.249642 -0.249642)
							(end -0.2794 -0.1778)
						)
						(arc
							(start -0.2794 0.1778)
							(mid -0.249642 0.249642)
							(end -0.1778 0.2794)
						)
						(arc
							(start 0.1778 0.2794)
							(mid 0.249642 0.249642)
							(end 0.2794 0.1778)
						)
						(arc
							(start 0.2794 -0.1778)
							(mid 0.249642 -0.249642)
							(end 0.1778 -0.2794)
						)
					)
					(width 0)
					(fill yes)
				)
			)
		)
		(pad "2" smd custom
			(at 0 0.4445 180)
			(size 0.1397 0.1397)
			(layers "F.Cu" "F.Mask" "F.Paste")
			(net "CLKGEN_N3")
			(options
				(clearance outline)
				(anchor circle)
			)
			(primitives
				(gr_poly
					(pts
						(arc
							(start -0.1778 -0.2794)
							(mid -0.249642 -0.249642)
							(end -0.2794 -0.1778)
						)
						(arc
							(start -0.2794 0.1778)
							(mid -0.249642 0.249642)
							(end -0.1778 0.2794)
						)
						(arc
							(start 0.1778 0.2794)
							(mid 0.249642 0.249642)
							(end 0.2794 0.1778)
						)
						(arc
							(start 0.2794 -0.1778)
							(mid 0.249642 -0.249642)
							(end 0.1778 -0.2794)
						)
					)
					(width 0)
					(fill yes)
				)
			)
		)
	)
	(footprint ""
		(layer "F.Cu")
		(at 41.712388 -116.311426)
		(property "Reference" "TP156"
			(at 0 0 0)
			(layer "F.SilkS")
			(hide yes)
			(effects
				(font
					(size 1.27 1.27)
				)
			)
		)
		(property "Value" "TPAD28-2-GP"
			(at -0.0127 -1.6637 0)
			(unlocked yes)
			(layer "F.Fab")
			(hide yes)
			(effects
				(font
					(size 1.016 1.016)
					(thickness 0.1524)
				)
			)
		)
		(property "Device Type" "TPAD28"
			(at -0.0127 -3.1877 0)
			(unlocked yes)
			(layer "F.Fab")
			(hide yes)
			(effects
				(font
					(size 1.016 1.016)
					(thickness 0.1524)
				)
			)
		)
		(duplicate_pad_numbers_are_jumpers no)
		(fp_poly
			(pts
				(arc
					(start 0.3556 0)
					(mid -0.3556 0)
					(end 0.3556 0)
				)
			)
			(stroke
				(width 0)
				(type default)
			)
			(fill no)
			(layer "F.CrtYd")
		)
		(fp_poly
			(pts
				(arc
					(start 0.6096 0)
					(mid -0.6096 0)
					(end 0.6096 0)
				)
			)
			(stroke
				(width 0)
				(type default)
			)
			(fill no)
			(layer "F.Fab")
		)
		(pad "1" smd circle
			(at 0 0)
			(size 0.7112 0.7112)
			(layers "F.Cu" "F.Mask" "F.Paste")
			(net "TP_GPIOT7")
		)
	)
)
